(kicad_pcb
	(version 20260206)
	(generator "pcbnew")
	(generator_version "10.0")
	(general
		(thickness 1.6)
		(legacy_teardrops no)
	)
	(paper "A4")
	(title_block
		(title "03242023_DA0F0TMBIJ0_F0T_Motherboard_J_brd_V01_OCP.brd")
		(comment 1 "Grand Teton / footprints 2077-2083 of 6105")
	)
	(layers
		(0 "F.Cu" signal "TOP")
		(4 "In1.Cu" signal "GND")
		(6 "In2.Cu" signal "IN1")
		(8 "In3.Cu" signal "GND1")
		(10 "In4.Cu" signal "IN2")
		(12 "In5.Cu" signal "GND2")
		(14 "In6.Cu" signal "IN3")
		(16 "In7.Cu" signal "GND3")
		(18 "In8.Cu" signal "VCC")
		(20 "In9.Cu" signal "VCC1")
		(22 "In10.Cu" signal "GND4")
		(24 "In11.Cu" signal "IN4")
		(26 "In12.Cu" signal "GND5")
		(28 "In13.Cu" signal "IN5")
		(30 "In14.Cu" signal "GND6")
		(32 "In15.Cu" signal "IN6")
		(34 "In16.Cu" signal "GND7")
		(2 "B.Cu" signal "BOTTOM")
		(9 "F.Adhes" user "F.Adhesive")
		(11 "B.Adhes" user "B.Adhesive")
		(13 "F.Paste" user "Package Geometry/Pastemask Top")
		(15 "B.Paste" user "Package Geometry/Pastemask Bottom")
		(5 "F.SilkS" user "Ref Des/Silkscreen Top")
		(7 "B.SilkS" user "Ref Des/Silkscreen Bottom")
		(1 "F.Mask" user "Board Geometry/Soldermask Top")
		(3 "B.Mask" user "Board Geometry/Soldermask Bottom")
		(17 "Dwgs.User" user "User.Drawings")
		(19 "Cmts.User" user "User.Comments")
		(21 "Eco1.User" user "User.Eco1")
		(23 "Eco2.User" user "User.Eco2")
		(25 "Edge.Cuts" user "Board Geometry/Outline")
		(27 "Margin" user)
		(31 "F.CrtYd" user "Package Geometry/Place Bound Top")
		(29 "B.CrtYd" user "Package Geometry/Place Bound Bottom")
		(35 "F.Fab" user "Ref Des/Assembly Top")
		(33 "B.Fab" user "Ref Des/Assembly Bottom")
	)
	(footprint ""
		(layer "F.Cu")
		(at 106.342434 -247.715278 90)
		(property "Reference" "C227"
			(at 0 0 90)
			(layer "F.SilkS")
			(hide yes)
			(effects
				(font
					(size 1.27 1.27)
				)
			)
		)
		(property "Value" ""
			(at 0 0 90)
			(layer "F.Fab")
			(effects
				(font
					(size 1.27 1.27)
				)
			)
		)
		(duplicate_pad_numbers_are_jumpers no)
		(fp_line
			(start 0.7874 -0.4064)
			(end 0.7874 0.4064)
			(stroke
				(width 0.1524)
				(type default)
			)
			(layer "F.SilkS")
		)
		(fp_line
			(start -0.7874 -0.4064)
			(end 0.7874 -0.4064)
			(stroke
				(width 0.1524)
				(type default)
			)
			(layer "F.SilkS")
		)
		(fp_line
			(start 0.7874 0.4064)
			(end -0.7874 0.4064)
			(stroke
				(width 0.1524)
				(type default)
			)
			(layer "F.SilkS")
		)
		(fp_line
			(start -0.7874 0.4064)
			(end -0.7874 -0.4064)
			(stroke
				(width 0.1524)
				(type default)
			)
			(layer "F.SilkS")
		)
		(fp_line
			(start -0.12065 -0.305054)
			(end -0.12065 -0.2794)
			(stroke
				(width 0.1)
				(type default)
			)
			(layer "F.Fab")
		)
		(fp_line
			(start -0.67945 -0.305054)
			(end -0.12065 -0.305054)
			(stroke
				(width 0.1)
				(type default)
			)
			(layer "F.Fab")
		)
		(fp_line
			(start 0.67945 -0.3048)
			(end 0.67945 0.3048)
			(stroke
				(width 0.1)
				(type default)
			)
			(layer "F.Fab")
		)
		(fp_line
			(start 0.12065 -0.3048)
			(end 0.67945 -0.3048)
			(stroke
				(width 0.1)
				(type default)
			)
			(layer "F.Fab")
		)
		(fp_line
			(start 0.12065 -0.2794)
			(end 0.12065 -0.3048)
			(stroke
				(width 0.1)
				(type default)
			)
			(layer "F.Fab")
		)
		(fp_line
			(start -0.12065 -0.2794)
			(end 0.12065 -0.2794)
			(stroke
				(width 0.1)
				(type default)
			)
			(layer "F.Fab")
		)
		(fp_line
			(start 0.120396 0.2794)
			(end -0.12065 0.2794)
			(stroke
				(width 0.1)
				(type default)
			)
			(layer "F.Fab")
		)
		(fp_line
			(start -0.12065 0.2794)
			(end -0.12065 0.3048)
			(stroke
				(width 0.1)
				(type default)
			)
			(layer "F.Fab")
		)
		(fp_line
			(start 0.67945 0.3048)
			(end 0.120396 0.3048)
			(stroke
				(width 0.1)
				(type default)
			)
			(layer "F.Fab")
		)
		(fp_line
			(start 0.120396 0.3048)
			(end 0.120396 0.2794)
			(stroke
				(width 0.1)
				(type default)
			)
			(layer "F.Fab")
		)
		(fp_line
			(start -0.12065 0.3048)
			(end -0.67945 0.3048)
			(stroke
				(width 0.1)
				(type default)
			)
			(layer "F.Fab")
		)
		(fp_line
			(start -0.67945 0.3048)
			(end -0.67945 -0.305054)
			(stroke
				(width 0.1)
				(type default)
			)
			(layer "F.Fab")
		)
		(pad "1" smd circle
			(at -0.40005 0 90)
			(size 0 0)
			(layers "F.Cu" "F.Mask" "F.Paste")
			(net "PVCCIN_CPU1")
		)
		(pad "2" smd circle
			(at 0.40005 0 90)
			(size 0 0)
			(layers "F.Cu" "F.Mask" "F.Paste")
			(net "GND")
		)
	)
	(footprint ""
		(layer "F.Cu")
		(at 250.890278 -92.36964)
		(property "Reference" "R106"
			(at 0 0 0)
			(layer "F.SilkS")
			(hide yes)
			(effects
				(font
					(size 1.27 1.27)
				)
			)
		)
		(property "Value" ""
			(at 0 0 0)
			(layer "F.Fab")
			(effects
				(font
					(size 1.27 1.27)
				)
			)
		)
		(duplicate_pad_numbers_are_jumpers no)
		(fp_line
			(start -0.7874 -0.4064)
			(end 0.7874 -0.4064)
			(stroke
				(width 0.1524)
				(type default)
			)
			(layer "F.SilkS")
		)
		(fp_line
			(start -0.7874 0.4064)
			(end -0.7874 -0.4064)
			(stroke
				(width 0.1524)
				(type default)
			)
			(layer "F.SilkS")
		)
		(fp_line
			(start 0.7874 -0.4064)
			(end 0.7874 0.4064)
			(stroke
				(width 0.1524)
				(type default)
			)
			(layer "F.SilkS")
		)
		(fp_line
			(start 0.7874 0.4064)
			(end -0.7874 0.4064)
			(stroke
				(width 0.1524)
				(type default)
			)
			(layer "F.SilkS")
		)
		(fp_line
			(start -0.67945 -0.305054)
			(end -0.12065 -0.305054)
			(stroke
				(width 0.1)
				(type default)
			)
			(layer "F.Fab")
		)
		(fp_line
			(start -0.67945 0.3048)
			(end -0.67945 -0.305054)
			(stroke
				(width 0.1)
				(type default)
			)
			(layer "F.Fab")
		)
		(fp_line
			(start -0.12065 -0.305054)
			(end -0.12065 -0.2794)
			(stroke
				(width 0.1)
				(type default)
			)
			(layer "F.Fab")
		)
		(fp_line
			(start -0.12065 -0.2794)
			(end 0.12065 -0.2794)
			(stroke
				(width 0.1)
				(type default)
			)
			(layer "F.Fab")
		)
		(fp_line
			(start -0.12065 0.2794)
			(end -0.12065 0.3048)
			(stroke
				(width 0.1)
				(type default)
			)
			(layer "F.Fab")
		)
		(fp_line
			(start -0.12065 0.3048)
			(end -0.67945 0.3048)
			(stroke
				(width 0.1)
				(type default)
			)
			(layer "F.Fab")
		)
		(fp_line
			(start 0.120396 0.2794)
			(end -0.12065 0.2794)
			(stroke
				(width 0.1)
				(type default)
			)
			(layer "F.Fab")
		)
		(fp_line
			(start 0.120396 0.3048)
			(end 0.120396 0.2794)
			(stroke
				(width 0.1)
				(type default)
			)
			(layer "F.Fab")
		)
		(fp_line
			(start 0.12065 -0.3048)
			(end 0.67945 -0.3048)
			(stroke
				(width 0.1)
				(type default)
			)
			(layer "F.Fab")
		)
		(fp_line
			(start 0.12065 -0.2794)
			(end 0.12065 -0.3048)
			(stroke
				(width 0.1)
				(type default)
			)
			(layer "F.Fab")
		)
		(fp_line
			(start 0.67945 -0.3048)
			(end 0.67945 0.3048)
			(stroke
				(width 0.1)
				(type default)
			)
			(layer "F.Fab")
		)
		(fp_line
			(start 0.67945 0.3048)
			(end 0.120396 0.3048)
			(stroke
				(width 0.1)
				(type default)
			)
			(layer "F.Fab")
		)
		(pad "1" smd circle
			(at -0.40005 0)
			(size 0 0)
			(layers "F.Cu" "F.Mask" "F.Paste")
			(net "GND")
		)
		(pad "2" smd circle
			(at 0.40005 0)
			(size 0 0)
			(layers "F.Cu" "F.Mask" "F.Paste")
			(net "FM_PLD_CLKS_DEV_EN")
		)
	)
	(footprint ""
		(layer "F.Cu")
		(at 7.24916 -99.346766)
		(property "Reference" "Y4"
			(at -1.9558 -2.748788 0)
			(unlocked yes)
			(layer "F.SilkS")
			(effects
				(font
					(size 0.7874 0.5842)
					(thickness 0.1524)
				)
				(justify left)
			)
		)
		(property "Value" ""
			(at 0 0 0)
			(layer "F.Fab")
			(effects
				(font
					(size 1.27 1.27)
				)
			)
		)
		(duplicate_pad_numbers_are_jumpers no)
		(fp_line
			(start -1.2446 -1.4986)
			(end -1.2446 1.4986)
			(stroke
				(width 0.1524)
				(type default)
			)
			(layer "F.SilkS")
		)
		(fp_line
			(start -1.2446 1.4986)
			(end 1.2446 1.4986)
			(stroke
				(width 0.1524)
				(type default)
			)
			(layer "F.SilkS")
		)
		(fp_line
			(start 1.2446 -1.4986)
			(end -1.2446 -1.4986)
			(stroke
				(width 0.1524)
				(type default)
			)
			(layer "F.SilkS")
		)
		(fp_line
			(start 1.2446 1.4986)
			(end 1.2446 -1.4986)
			(stroke
				(width 0.1524)
				(type default)
			)
			(layer "F.SilkS")
		)
		(fp_poly
			(pts
				(xy -2.72288 -1.357884) (xy -1.70688 -0.849884) (xy -2.72288 -0.341884)
			)
			(stroke
				(width 0)
				(type default)
			)
			(fill yes)
			(layer "F.SilkS")
		)
		(fp_line
			(start -1.050036 -1.299972)
			(end -1.050036 1.299972)
			(stroke
				(width 0.1)
				(type default)
			)
			(layer "F.Fab")
		)
		(fp_line
			(start -1.050036 1.299972)
			(end 1.050036 1.299972)
			(stroke
				(width 0.1)
				(type default)
			)
			(layer "F.Fab")
		)
		(fp_line
			(start 1.050036 -1.299972)
			(end -1.050036 -1.299972)
			(stroke
				(width 0.1)
				(type default)
			)
			(layer "F.Fab")
		)
		(fp_line
			(start 1.050036 1.299972)
			(end 1.050036 -1.299972)
			(stroke
				(width 0.1)
				(type default)
			)
			(layer "F.Fab")
		)
		(fp_poly
			(pts
				(xy -2.4638 -1.357884) (xy -2.4638 -0.341884) (xy -1.4478 -0.849884)
			)
			(stroke
				(width 0)
				(type default)
			)
			(fill yes)
			(layer "F.Fab")
		)
		(pad "1" smd rect
			(at -0.649986 -0.849884 180)
			(size 0.9144 1.016)
			(layers "F.Cu" "F.Mask" "F.Paste")
			(net "USB_HUB_XTAL_IN")
		)
		(pad "2" smd rect
			(at -0.649986 0.849884 180)
			(size 0.9144 1.016)
			(layers "F.Cu" "F.Mask" "F.Paste")
			(net "GND")
		)
		(pad "3" smd rect
			(at 0.649986 0.849884 180)
			(size 0.9144 1.016)
			(layers "F.Cu" "F.Mask" "F.Paste")
			(net "USB_HUB_XTAL_OUT")
		)
		(pad "4" smd rect
			(at 0.649986 -0.849884 180)
			(size 0.9144 1.016)
			(layers "F.Cu" "F.Mask" "F.Paste")
			(net "GND")
		)
	)
	(footprint ""
		(layer "F.Cu")
		(at 10.63498 -383.867914)
		(property "Reference" "H30"
			(at -2.6416 -7.392924 0)
			(unlocked yes)
			(layer "F.SilkS")
			(effects
				(font
					(size 0.7874 0.5842)
					(thickness 0.1524)
				)
				(justify left)
			)
		)
		(property "Value" ""
			(at 0 0 0)
			(layer "F.Fab")
			(effects
				(font
					(size 1.27 1.27)
				)
			)
		)
		(duplicate_pad_numbers_are_jumpers no)
		(fp_circle
			(center 0 0)
			(end 2.4003 0)
			(stroke
				(width 0.1524)
				(type default)
			)
			(fill no)
			(layer "F.SilkS")
		)
		(fp_circle
			(center 0 0)
			(end 6.5913 0)
			(stroke
				(width 0.1524)
				(type default)
			)
			(fill no)
			(layer "B.SilkS")
		)
		(fp_circle
			(center 0 0)
			(end 6.5913 0)
			(stroke
				(width 0.1)
				(type default)
			)
			(fill no)
			(layer "B.Fab")
		)
		(fp_circle
			(center 0 0)
			(end 2.4003 0)
			(stroke
				(width 0.1)
				(type default)
			)
			(fill no)
			(layer "F.Fab")
		)
		(pad "" np_thru_hole circle
			(at 0 0)
			(size 3.175 3.175)
			(drill 3.175)
			(layers "*.Cu" "*.Mask")
			(clearance 0.381)
			(thermal_gap 0.381)
		)
		(zone
			(layers "F.Cu" "B.Cu" "In1.Cu" "In2.Cu" "In3.Cu" "In4.Cu" "In5.Cu" "In6.Cu"
				"In7.Cu" "In8.Cu" "In9.Cu" "In10.Cu" "In11.Cu" "In12.Cu" "In13.Cu" "In14.Cu"
				"In15.Cu" "In16.Cu"
			)
			(hatch none 0.5)
			(connect_pads
				(clearance 0)
			)
			(min_thickness 0.25)
			(keepout
				(tracks not_allowed)
				(vias allowed)
				(pads allowed)
				(copperpour not_allowed)
				(footprints allowed)
			)
			(placement
				(enabled no)
				(sheetname "")
			)
			(fill
				(thermal_gap 0.5)
				(thermal_bridge_width 0.5)
				(island_removal_mode 0)
			)
			(polygon
				(pts
					(arc
						(start 12.73048 -383.867914)
						(mid 8.53948 -383.867914)
						(end 12.73048 -383.867914)
					)
				)
			)
		)
	)
	(footprint ""
		(layer "F.Cu")
		(at 166.07028 -21.783548 90)
		(property "Reference" "R1356"
			(at 0 0 90)
			(layer "F.SilkS")
			(hide yes)
			(effects
				(font
					(size 1.27 1.27)
				)
			)
		)
		(property "Value" ""
			(at 0 0 90)
			(layer "F.Fab")
			(effects
				(font
					(size 1.27 1.27)
				)
			)
		)
		(duplicate_pad_numbers_are_jumpers no)
		(fp_line
			(start 0.7874 -0.4064)
			(end 0.7874 0.4064)
			(stroke
				(width 0.1524)
				(type default)
			)
			(layer "F.SilkS")
		)
		(fp_line
			(start -0.7874 -0.4064)
			(end 0.7874 -0.4064)
			(stroke
				(width 0.1524)
				(type default)
			)
			(layer "F.SilkS")
		)
		(fp_line
			(start 0.7874 0.4064)
			(end -0.7874 0.4064)
			(stroke
				(width 0.1524)
				(type default)
			)
			(layer "F.SilkS")
		)
		(fp_line
			(start -0.7874 0.4064)
			(end -0.7874 -0.4064)
			(stroke
				(width 0.1524)
				(type default)
			)
			(layer "F.SilkS")
		)
		(fp_line
			(start -0.12065 -0.305054)
			(end -0.12065 -0.2794)
			(stroke
				(width 0.1)
				(type default)
			)
			(layer "F.Fab")
		)
		(fp_line
			(start -0.67945 -0.305054)
			(end -0.12065 -0.305054)
			(stroke
				(width 0.1)
				(type default)
			)
			(layer "F.Fab")
		)
		(fp_line
			(start 0.67945 -0.3048)
			(end 0.67945 0.3048)
			(stroke
				(width 0.1)
				(type default)
			)
			(layer "F.Fab")
		)
		(fp_line
			(start 0.12065 -0.3048)
			(end 0.67945 -0.3048)
			(stroke
				(width 0.1)
				(type default)
			)
			(layer "F.Fab")
		)
		(fp_line
			(start 0.12065 -0.2794)
			(end 0.12065 -0.3048)
			(stroke
				(width 0.1)
				(type default)
			)
			(layer "F.Fab")
		)
		(fp_line
			(start -0.12065 -0.2794)
			(end 0.12065 -0.2794)
			(stroke
				(width 0.1)
				(type default)
			)
			(layer "F.Fab")
		)
		(fp_line
			(start 0.120396 0.2794)
			(end -0.12065 0.2794)
			(stroke
				(width 0.1)
				(type default)
			)
			(layer "F.Fab")
		)
		(fp_line
			(start -0.12065 0.2794)
			(end -0.12065 0.3048)
			(stroke
				(width 0.1)
				(type default)
			)
			(layer "F.Fab")
		)
		(fp_line
			(start 0.67945 0.3048)
			(end 0.120396 0.3048)
			(stroke
				(width 0.1)
				(type default)
			)
			(layer "F.Fab")
		)
		(fp_line
			(start 0.120396 0.3048)
			(end 0.120396 0.2794)
			(stroke
				(width 0.1)
				(type default)
			)
			(layer "F.Fab")
		)
		(fp_line
			(start -0.12065 0.3048)
			(end -0.67945 0.3048)
			(stroke
				(width 0.1)
				(type default)
			)
			(layer "F.Fab")
		)
		(fp_line
			(start -0.67945 0.3048)
			(end -0.67945 -0.305054)
			(stroke
				(width 0.1)
				(type default)
			)
			(layer "F.Fab")
		)
		(pad "1" smd circle
			(at -0.40005 0 90)
			(size 0 0)
			(layers "F.Cu" "F.Mask" "F.Paste")
			(net "RMII_BMC_OCP_RX_ER")
		)
		(pad "2" smd circle
			(at 0.40005 0 90)
			(size 0 0)
			(layers "F.Cu" "F.Mask" "F.Paste")
			(net "GND")
		)
	)
	(footprint ""
		(layer "F.Cu")
		(at 130.233674 -402.371052 -90)
		(property "Reference" "C748"
			(at 0 0 270)
			(layer "F.SilkS")
			(hide yes)
			(effects
				(font
					(size 1.27 1.27)
				)
			)
		)
		(property "Value" ""
			(at 0 0 270)
			(layer "F.Fab")
			(effects
				(font
					(size 1.27 1.27)
				)
			)
		)
		(duplicate_pad_numbers_are_jumpers no)
		(fp_line
			(start -0.299974 0.150114)
			(end -0.299974 -0.150114)
			(stroke
				(width 0.1)
				(type default)
			)
			(layer "F.Fab")
		)
		(fp_line
			(start 0.299974 0.150114)
			(end -0.299974 0.150114)
			(stroke
				(width 0.1)
				(type default)
			)
			(layer "F.Fab")
		)
		(fp_line
			(start -0.299974 -0.150114)
			(end 0.299974 -0.150114)
			(stroke
				(width 0.1)
				(type default)
			)
			(layer "F.Fab")
		)
		(fp_line
			(start 0.299974 -0.150114)
			(end 0.299974 0.150114)
			(stroke
				(width 0.1)
				(type default)
			)
			(layer "F.Fab")
		)
		(pad "1" smd rect
			(at -0.2667 0 270)
			(size 0.3048 0.381)
			(layers "F.Cu" "F.Mask" "F.Paste")
			(net "P5E_CPU1_PE2_TX_C_DN<12>")
		)
		(pad "2" smd rect
			(at 0.2667 0 270)
			(size 0.3048 0.381)
			(layers "F.Cu" "F.Mask" "F.Paste")
			(net "P5E_CPU1_PE2_TX_DN<12>")
		)
	)
	(footprint ""
		(layer "F.Cu")
		(at 33.021524 -124.99721 90)
		(property "Reference" "R2563"
			(at 0 0 90)
			(layer "F.SilkS")
			(hide yes)
			(effects
				(font
					(size 1.27 1.27)
				)
			)
		)
		(property "Value" ""
			(at 0 0 90)
			(layer "F.Fab")
			(effects
				(font
					(size 1.27 1.27)
				)
			)
		)
		(duplicate_pad_numbers_are_jumpers no)
		(fp_line
			(start 0.7874 -0.4064)
			(end 0.7874 0.4064)
			(stroke
				(width 0.1524)
				(type default)
			)
			(layer "F.SilkS")
		)
		(fp_line
			(start -0.7874 -0.4064)
			(end 0.7874 -0.4064)
			(stroke
				(width 0.1524)
				(type default)
			)
			(layer "F.SilkS")
		)
		(fp_line
			(start 0.7874 0.4064)
			(end -0.7874 0.4064)
			(stroke
				(width 0.1524)
				(type default)
			)
			(layer "F.SilkS")
		)
		(fp_line
			(start -0.7874 0.4064)
			(end -0.7874 -0.4064)
			(stroke
				(width 0.1524)
				(type default)
			)
			(layer "F.SilkS")
		)
		(fp_line
			(start -0.12065 -0.305054)
			(end -0.12065 -0.2794)
			(stroke
				(width 0.1)
				(type default)
			)
			(layer "F.Fab")
		)
		(fp_line
			(start -0.67945 -0.305054)
			(end -0.12065 -0.305054)
			(stroke
				(width 0.1)
				(type default)
			)
			(layer "F.Fab")
		)
		(fp_line
			(start 0.67945 -0.3048)
			(end 0.67945 0.3048)
			(stroke
				(width 0.1)
				(type default)
			)
			(layer "F.Fab")
		)
		(fp_line
			(start 0.12065 -0.3048)
			(end 0.67945 -0.3048)
			(stroke
				(width 0.1)
				(type default)
			)
			(layer "F.Fab")
		)
		(fp_line
			(start 0.12065 -0.2794)
			(end 0.12065 -0.3048)
			(stroke
				(width 0.1)
				(type default)
			)
			(layer "F.Fab")
		)
		(fp_line
			(start -0.12065 -0.2794)
			(end 0.12065 -0.2794)
			(stroke
				(width 0.1)
				(type default)
			)
			(layer "F.Fab")
		)
		(fp_line
			(start 0.120396 0.2794)
			(end -0.12065 0.2794)
			(stroke
				(width 0.1)
				(type default)
			)
			(layer "F.Fab")
		)
		(fp_line
			(start -0.12065 0.2794)
			(end -0.12065 0.3048)
			(stroke
				(width 0.1)
				(type default)
			)
			(layer "F.Fab")
		)
		(fp_line
			(start 0.67945 0.3048)
			(end 0.120396 0.3048)
			(stroke
				(width 0.1)
				(type default)
			)
			(layer "F.Fab")
		)
		(fp_line
			(start 0.120396 0.3048)
			(end 0.120396 0.2794)
			(stroke
				(width 0.1)
				(type default)
			)
			(layer "F.Fab")
		)
		(fp_line
			(start -0.12065 0.3048)
			(end -0.67945 0.3048)
			(stroke
				(width 0.1)
				(type default)
			)
			(layer "F.Fab")
		)
		(fp_line
			(start -0.67945 0.3048)
			(end -0.67945 -0.305054)
			(stroke
				(width 0.1)
				(type default)
			)
			(layer "F.Fab")
		)
		(pad "1" smd circle
			(at -0.40005 0 90)
			(size 0 0)
			(layers "F.Cu" "F.Mask" "F.Paste")
			(net "SMB_VR_3V3AUX_SDA_R")
		)
		(pad "2" smd circle
			(at 0.40005 0 90)
			(size 0 0)
			(layers "F.Cu" "F.Mask" "F.Paste")
			(net "SMB_DIO_PVCCINFAON_CPU1")
		)
	)
)
